# S9S_MB_2U (Grand Teton) — schematic netlist excerpt (pin names and nets, part order shuffled) for the footprints in the layout excerpt that follows; sources: Cadence DE-HDL packaged netlist, KiCad conversion of 03242023_DA0F0TMBIJ0_F0T_Motherboard_J_brd_V01_OCP.brd

C387  Q_CAP  47UF 4V 20% X6S  pkg C0805  page 75 : A = PVCCIN_CPU0 ; B = GND
PC1676  Q_CAP  22UF 16V 20% X6S  pkg C0805  page 272 : A = SW_P12V_PVCCFA_EHV_FIVRA_CPU0_R ; B = GND
PC2172  Q_CAPP  330UF 2.5V +10/-35% SPCAP  pkg SMLF  page 289 : A = PVCCFA_EHV_FIVRA_CPU1 ; B = GND

(kicad_pcb
	(version 20260206)
	(generator "pcbnew")
	(generator_version "10.0")
	(general
		(thickness 1.6)
		(legacy_teardrops no)
	)
	(paper "A4")
	(title_block
		(title "03242023_DA0F0TMBIJ0_F0T_Motherboard_J_brd_V01_OCP.brd")
		(comment 1 "Grand Teton / footprints 4821-4823 of 6105")
	)
	(layers
		(0 "F.Cu" signal "TOP")
		(4 "In1.Cu" signal "GND")
		(6 "In2.Cu" signal "IN1")
		(8 "In3.Cu" signal "GND1")
		(10 "In4.Cu" signal "IN2")
		(12 "In5.Cu" signal "GND2")
		(14 "In6.Cu" signal "IN3")
		(16 "In7.Cu" signal "GND3")
		(18 "In8.Cu" signal "VCC")
		(20 "In9.Cu" signal "VCC1")
		(22 "In10.Cu" signal "GND4")
		(24 "In11.Cu" signal "IN4")
		(26 "In12.Cu" signal "GND5")
		(28 "In13.Cu" signal "IN5")
		(30 "In14.Cu" signal "GND6")
		(32 "In15.Cu" signal "IN6")
		(34 "In16.Cu" signal "GND7")
		(2 "B.Cu" signal "BOTTOM")
		(9 "F.Adhes" user "F.Adhesive")
		(11 "B.Adhes" user "B.Adhesive")
		(13 "F.Paste" user "Package Geometry/Pastemask Top")
		(15 "B.Paste" user "Package Geometry/Pastemask Bottom")
		(5 "F.SilkS" user "Ref Des/Silkscreen Top")
		(7 "B.SilkS" user "Ref Des/Silkscreen Bottom")
		(1 "F.Mask" user "Board Geometry/Soldermask Top")
		(3 "B.Mask" user "Board Geometry/Soldermask Bottom")
		(17 "Dwgs.User" user "User.Drawings")
		(19 "Cmts.User" user "User.Comments")
		(21 "Eco1.User" user "User.Eco1")
		(23 "Eco2.User" user "User.Eco2")
		(25 "Edge.Cuts" user "Board Geometry/Outline")
		(27 "Margin" user)
		(31 "F.CrtYd" user "Package Geometry/Place Bound Top")
		(29 "B.CrtYd" user "Package Geometry/Place Bound Bottom")
		(35 "F.Fab" user "Ref Des/Assembly Top")
		(33 "B.Fab" user "Ref Des/Assembly Bottom")
	)
	(footprint ""
		(layer "B.Cu")
		(at 364.342934 -241.142266 -90)
		(property "Reference" "C387"
			(at 0 0 90)
			(layer "B.SilkS")
			(hide yes)
			(effects
				(font
					(size 1.27 1.27)
				)
				(justify mirror)
			)
		)
		(property "Value" ""
			(at 0 0 90)
			(layer "B.Fab")
			(effects
				(font
					(size 1.27 1.27)
				)
				(justify mirror)
			)
		)
		(duplicate_pad_numbers_are_jumpers no)
		(fp_line
			(start -1.524 0.762)
			(end 1.524 0.762)
			(stroke
				(width 0.1524)
				(type default)
			)
			(layer "B.SilkS")
		)
		(fp_line
			(start 1.524 0.762)
			(end 1.524 -0.762)
			(stroke
				(width 0.1524)
				(type default)
			)
			(layer "B.SilkS")
		)
		(fp_line
			(start -1.524 -0.762)
			(end -1.524 0.762)
			(stroke
				(width 0.1524)
				(type default)
			)
			(layer "B.SilkS")
		)
		(fp_line
			(start 1.524 -0.762)
			(end -1.524 -0.762)
			(stroke
				(width 0.1524)
				(type default)
			)
			(layer "B.SilkS")
		)
		(fp_line
			(start -1.1049 0.724916)
			(end -1.1049 -0.724916)
			(stroke
				(width 0.1)
				(type default)
			)
			(layer "B.Fab")
		)
		(fp_line
			(start 1.1049 0.724916)
			(end -1.1049 0.724916)
			(stroke
				(width 0.1)
				(type default)
			)
			(layer "B.Fab")
		)
		(fp_line
			(start -1.1049 -0.724916)
			(end 1.1049 -0.724916)
			(stroke
				(width 0.1)
				(type default)
			)
			(layer "B.Fab")
		)
		(fp_line
			(start 1.1049 -0.724916)
			(end 1.1049 0.724916)
			(stroke
				(width 0.1)
				(type default)
			)
			(layer "B.Fab")
		)
		(pad "1" smd rect
			(at 0.889 0 270)
			(size 1.016 1.27)
			(layers "B.Cu" "B.Mask" "B.Paste")
			(net "PVCCIN_CPU0")
		)
		(pad "2" smd rect
			(at -0.889 0 270)
			(size 1.016 1.27)
			(layers "B.Cu" "B.Mask" "B.Paste")
			(net "GND")
		)
	)
	(footprint ""
		(layer "B.Cu")
		(at 431.248058 -366.70869 180)
		(property "Reference" "PC1676"
			(at 0 0 0)
			(layer "B.SilkS")
			(hide yes)
			(effects
				(font
					(size 1.27 1.27)
				)
				(justify mirror)
			)
		)
		(property "Value" ""
			(at 0 0 0)
			(layer "B.Fab")
			(effects
				(font
					(size 1.27 1.27)
				)
				(justify mirror)
			)
		)
		(duplicate_pad_numbers_are_jumpers no)
		(fp_line
			(start 1.524 0.762)
			(end 1.524 -0.762)
			(stroke
				(width 0.1524)
				(type default)
			)
			(layer "B.SilkS")
		)
		(fp_line
			(start 1.524 -0.762)
			(end -1.524 -0.762)
			(stroke
				(width 0.1524)
				(type default)
			)
			(layer "B.SilkS")
		)
		(fp_line
			(start -1.524 0.762)
			(end 1.524 0.762)
			(stroke
				(width 0.1524)
				(type default)
			)
			(layer "B.SilkS")
		)
		(fp_line
			(start -1.524 -0.762)
			(end -1.524 0.762)
			(stroke
				(width 0.1524)
				(type default)
			)
			(layer "B.SilkS")
		)
		(fp_line
			(start 1.1049 0.724916)
			(end -1.1049 0.724916)
			(stroke
				(width 0.1)
				(type default)
			)
			(layer "B.Fab")
		)
		(fp_line
			(start 1.1049 -0.724916)
			(end 1.1049 0.724916)
			(stroke
				(width 0.1)
				(type default)
			)
			(layer "B.Fab")
		)
		(fp_line
			(start -1.1049 0.724916)
			(end -1.1049 -0.724916)
			(stroke
				(width 0.1)
				(type default)
			)
			(layer "B.Fab")
		)
		(fp_line
			(start -1.1049 -0.724916)
			(end 1.1049 -0.724916)
			(stroke
				(width 0.1)
				(type default)
			)
			(layer "B.Fab")
		)
		(pad "1" smd rect
			(at 0.889 0 180)
			(size 1.016 1.27)
			(layers "B.Cu" "B.Mask" "B.Paste")
			(net "SW_P12V_PVCCFA_EHV_FIVRA_CPU0_R")
		)
		(pad "2" smd rect
			(at -0.889 0 180)
			(size 1.016 1.27)
			(layers "B.Cu" "B.Mask" "B.Paste")
			(net "GND")
		)
	)
	(footprint ""
		(layer "B.Cu")
		(at 41.535858 -346.579952 -90)
		(property "Reference" "PC2172"
			(at 0 0 90)
			(layer "B.SilkS")
			(hide yes)
			(effects
				(font
					(size 1.27 1.27)
				)
				(justify mirror)
			)
		)
		(property "Value" ""
			(at 0 0 90)
			(layer "B.Fab")
			(effects
				(font
					(size 1.27 1.27)
				)
				(justify mirror)
			)
		)
		(duplicate_pad_numbers_are_jumpers no)
		(fp_line
			(start -4.533392 2.249932)
			(end 4.533392 2.249932)
			(stroke
				(width 0.1524)
				(type default)
			)
			(layer "B.SilkS")
		)
		(fp_line
			(start 4.533392 2.249932)
			(end 4.533392 -2.249932)
			(stroke
				(width 0.1524)
				(type default)
			)
			(layer "B.SilkS")
		)
		(fp_line
			(start -4.533392 -2.249932)
			(end -4.533392 2.249932)
			(stroke
				(width 0.1524)
				(type default)
			)
			(layer "B.SilkS")
		)
		(fp_line
			(start 4.533392 -2.249932)
			(end -4.533392 -2.249932)
			(stroke
				(width 0.1524)
				(type default)
			)
			(layer "B.SilkS")
		)
		(fp_poly
			(pts
				(xy 4.533392 -2.326132) (xy 5.39242 -2.326132) (xy 5.39242 2.326132) (xy 4.533392 2.326132)
			)
			(stroke
				(width 0)
				(type default)
			)
			(fill yes)
			(layer "B.SilkS")
		)
		(fp_line
			(start -3.750056 2.249932)
			(end 3.750056 2.249932)
			(stroke
				(width 0.1)
				(type default)
			)
			(layer "B.Fab")
		)
		(fp_line
			(start 3.750056 2.249932)
			(end 3.750056 -2.249932)
			(stroke
				(width 0.1)
				(type default)
			)
			(layer "B.Fab")
		)
		(fp_line
			(start -3.750056 -2.249932)
			(end -3.750056 2.249932)
			(stroke
				(width 0.1)
				(type default)
			)
			(layer "B.Fab")
		)
		(fp_line
			(start 3.750056 -2.249932)
			(end -3.750056 -2.249932)
			(stroke
				(width 0.1)
				(type default)
			)
			(layer "B.Fab")
		)
		(fp_text user "+"
			(at 6.322314 0.786384 180)
			(unlocked yes)
			(layer "B.SilkS")
			(effects
				(font
					(size 1.905 1.4224)
					(thickness 0.1524)
				)
				(justify left mirror)
			)
		)
		(fp_text user "-"
			(at -4.8514 -0.14605 270)
			(unlocked yes)
			(layer "B.SilkS")
			(effects
				(font
					(size 1.905 1.4224)
					(thickness 0.1524)
				)
				(justify left mirror)
			)
		)
		(fp_text user "+"
			(at 6.322314 0.786384 180)
			(unlocked yes)
			(layer "B.Fab")
			(effects
				(font
					(size 1.905 1.4224)
					(thickness 0.1524)
				)
				(justify left mirror)
			)
		)
		(fp_text user "-"
			(at -4.8514 -0.14605 270)
			(unlocked yes)
			(layer "B.Fab")
			(effects
				(font
					(size 1.905 1.4224)
					(thickness 0.1524)
				)
				(justify left mirror)
			)
		)
		(pad "1" smd rect
			(at 3.199892 0 90)
			(size 2.413 2.8194)
			(layers "B.Cu" "B.Mask" "B.Paste")
			(net "PVCCFA_EHV_FIVRA_CPU1")
		)
		(pad "2" smd rect
			(at -3.199892 0 90)
			(size 2.413 2.8194)
			(layers "B.Cu" "B.Mask" "B.Paste")
			(net "GND")
		)
	)
)
